# T6G (Grand Teton) — schematic netlist excerpt (pin names and nets, part order shuffled) for the footprints in the layout excerpt that follows; sources: Cadence DE-HDL packaged netlist, KiCad conversion of 04192023_DAF0TMB3IC0_F0TG_MB_C_brd_V02_OCP.brd

R3217  Q_RES  100 1% CHIP  pkg 0402LF  page 138 : A = OCP_V3_2_ISO_BIF2_EN ; B = GND
C1573  Q_CAP_DIFFBUS  DIFF BUS_0.22UF 6.3V 20% X6S  pkg C0201  page 65 : \1\ = P5E_CPU0_G3_TX_C_DP<3> ; \2\ = P5E_CPU0_G3_TX_DP<3>
R860  Q_RES  0 5% CHIP  pkg 0201LF  page 342 : A = RST_RT_CPU1_P2_RESET_N ; B = RST_RT_CPU1_P2_RESET_R_N

(kicad_pcb
	(version 20260206)
	(generator "pcbnew")
	(generator_version "10.0")
	(general
		(thickness 1.6)
		(legacy_teardrops no)
	)
	(paper "A4")
	(title_block
		(title "04192023_DAF0TMB3IC0_F0TG_MB_C_brd_V02_OCP.brd")
		(comment 1 "Grand Teton / footprints 803-805 of 8354")
	)
	(layers
		(0 "F.Cu" signal "TOP")
		(4 "In1.Cu" signal "GND")
		(6 "In2.Cu" signal "IN1")
		(8 "In3.Cu" signal "GND1")
		(10 "In4.Cu" signal "IN2")
		(12 "In5.Cu" signal "GND2")
		(14 "In6.Cu" signal "IN3")
		(16 "In7.Cu" signal "GND3")
		(18 "In8.Cu" signal "VCC")
		(20 "In9.Cu" signal "VCC1")
		(22 "In10.Cu" signal "GND4")
		(24 "In11.Cu" signal "IN4")
		(26 "In12.Cu" signal "GND5")
		(28 "In13.Cu" signal "IN5")
		(30 "In14.Cu" signal "GND6")
		(32 "In15.Cu" signal "IN6")
		(34 "In16.Cu" signal "GND7")
		(2 "B.Cu" signal "BOTTOM")
		(9 "F.Adhes" user "F.Adhesive")
		(11 "B.Adhes" user "B.Adhesive")
		(13 "F.Paste" user "Package Geometry/Pastemask Top")
		(15 "B.Paste" user "Package Geometry/Pastemask Bottom")
		(5 "F.SilkS" user "Ref Des/Silkscreen Top")
		(7 "B.SilkS" user "Ref Des/Silkscreen Bottom")
		(1 "F.Mask" user "Board Geometry/Soldermask Top")
		(3 "B.Mask" user "Board Geometry/Soldermask Bottom")
		(17 "Dwgs.User" user "User.Drawings")
		(19 "Cmts.User" user "User.Comments")
		(21 "Eco1.User" user "User.Eco1")
		(23 "Eco2.User" user "User.Eco2")
		(25 "Edge.Cuts" user "Board Geometry/Outline")
		(27 "Margin" user)
		(31 "F.CrtYd" user "Package Geometry/Place Bound Top")
		(29 "B.CrtYd" user "Package Geometry/Place Bound Bottom")
		(35 "F.Fab" user "Ref Des/Assembly Top")
		(33 "B.Fab" user "Ref Des/Assembly Bottom")
	)
	(footprint ""
		(layer "F.Cu")
		(at 61.90488 -18.252948)
		(property "Reference" "R3217"
			(at 0 0 0)
			(layer "F.SilkS")
			(hide yes)
			(effects
				(font
					(size 1.27 1.27)
				)
			)
		)
		(property "Value" ""
			(at 0 0 0)
			(layer "F.Fab")
			(effects
				(font
					(size 1.27 1.27)
				)
			)
		)
		(duplicate_pad_numbers_are_jumpers no)
		(fp_line
			(start -0.7874 -0.4064)
			(end 0.7874 -0.4064)
			(stroke
				(width 0.1524)
				(type default)
			)
			(layer "F.SilkS")
		)
		(fp_line
			(start -0.7874 0.4064)
			(end -0.7874 -0.4064)
			(stroke
				(width 0.1524)
				(type default)
			)
			(layer "F.SilkS")
		)
		(fp_line
			(start 0.7874 -0.4064)
			(end 0.7874 0.4064)
			(stroke
				(width 0.1524)
				(type default)
			)
			(layer "F.SilkS")
		)
		(fp_line
			(start 0.7874 0.4064)
			(end -0.7874 0.4064)
			(stroke
				(width 0.1524)
				(type default)
			)
			(layer "F.SilkS")
		)
		(fp_line
			(start -0.67945 -0.305054)
			(end -0.12065 -0.305054)
			(stroke
				(width 0.1)
				(type default)
			)
			(layer "F.Fab")
		)
		(fp_line
			(start -0.67945 0.3048)
			(end -0.67945 -0.305054)
			(stroke
				(width 0.1)
				(type default)
			)
			(layer "F.Fab")
		)
		(fp_line
			(start -0.12065 -0.305054)
			(end -0.12065 -0.2794)
			(stroke
				(width 0.1)
				(type default)
			)
			(layer "F.Fab")
		)
		(fp_line
			(start -0.12065 -0.2794)
			(end 0.12065 -0.2794)
			(stroke
				(width 0.1)
				(type default)
			)
			(layer "F.Fab")
		)
		(fp_line
			(start -0.12065 0.2794)
			(end -0.12065 0.3048)
			(stroke
				(width 0.1)
				(type default)
			)
			(layer "F.Fab")
		)
		(fp_line
			(start -0.12065 0.3048)
			(end -0.67945 0.3048)
			(stroke
				(width 0.1)
				(type default)
			)
			(layer "F.Fab")
		)
		(fp_line
			(start 0.120396 0.2794)
			(end -0.12065 0.2794)
			(stroke
				(width 0.1)
				(type default)
			)
			(layer "F.Fab")
		)
		(fp_line
			(start 0.120396 0.3048)
			(end 0.120396 0.2794)
			(stroke
				(width 0.1)
				(type default)
			)
			(layer "F.Fab")
		)
		(fp_line
			(start 0.12065 -0.3048)
			(end 0.67945 -0.3048)
			(stroke
				(width 0.1)
				(type default)
			)
			(layer "F.Fab")
		)
		(fp_line
			(start 0.12065 -0.2794)
			(end 0.12065 -0.3048)
			(stroke
				(width 0.1)
				(type default)
			)
			(layer "F.Fab")
		)
		(fp_line
			(start 0.67945 -0.3048)
			(end 0.67945 0.3048)
			(stroke
				(width 0.1)
				(type default)
			)
			(layer "F.Fab")
		)
		(fp_line
			(start 0.67945 0.3048)
			(end 0.120396 0.3048)
			(stroke
				(width 0.1)
				(type default)
			)
			(layer "F.Fab")
		)
		(pad "1" smd circle
			(at -0.40005 0)
			(size 0 0)
			(layers "F.Cu" "F.Mask" "F.Paste")
			(net "OCP_V3_2_ISO_BIF2_EN")
		)
		(pad "2" smd circle
			(at 0.40005 0)
			(size 0 0)
			(layers "F.Cu" "F.Mask" "F.Paste")
			(net "GND")
		)
	)
	(footprint ""
		(layer "F.Cu")
		(at 143.350488 -394.903452 90)
		(property "Reference" "R860"
			(at 0 0 90)
			(layer "F.SilkS")
			(hide yes)
			(effects
				(font
					(size 1.27 1.27)
				)
			)
		)
		(property "Value" ""
			(at 0 0 90)
			(layer "F.Fab")
			(effects
				(font
					(size 1.27 1.27)
				)
			)
		)
		(duplicate_pad_numbers_are_jumpers no)
		(fp_line
			(start 0.32512 -0.175006)
			(end 0.32512 0.175006)
			(stroke
				(width 0.1)
				(type default)
			)
			(layer "F.Fab")
		)
		(fp_line
			(start -0.32512 -0.175006)
			(end 0.32512 -0.175006)
			(stroke
				(width 0.1)
				(type default)
			)
			(layer "F.Fab")
		)
		(fp_line
			(start 0.32512 0.175006)
			(end -0.32512 0.175006)
			(stroke
				(width 0.1)
				(type default)
			)
			(layer "F.Fab")
		)
		(fp_line
			(start -0.32512 0.175006)
			(end -0.32512 -0.175006)
			(stroke
				(width 0.1)
				(type default)
			)
			(layer "F.Fab")
		)
		(pad "1" smd rect
			(at -0.2667 0 90)
			(size 0.3048 0.381)
			(layers "F.Cu" "F.Mask" "F.Paste")
			(net "RST_RT_CPU1_P2_RESET_N")
		)
		(pad "2" smd rect
			(at 0.2667 0 270)
			(size 0.3048 0.381)
			(layers "F.Cu" "F.Mask" "F.Paste")
			(net "RST_RT_CPU1_P2_RESET_R_N")
		)
	)
	(footprint ""
		(layer "F.Cu")
		(at 424.755564 -16.100298 90)
		(property "Reference" "C1573"
			(at 0 0 90)
			(layer "F.SilkS")
			(hide yes)
			(effects
				(font
					(size 1.27 1.27)
				)
			)
		)
		(property "Value" ""
			(at 0 0 90)
			(layer "F.Fab")
			(effects
				(font
					(size 1.27 1.27)
				)
			)
		)
		(duplicate_pad_numbers_are_jumpers no)
		(fp_line
			(start 0.299974 -0.150114)
			(end 0.299974 0.150114)
			(stroke
				(width 0.1)
				(type default)
			)
			(layer "F.Fab")
		)
		(fp_line
			(start -0.299974 -0.150114)
			(end 0.299974 -0.150114)
			(stroke
				(width 0.1)
				(type default)
			)
			(layer "F.Fab")
		)
		(fp_line
			(start 0.299974 0.150114)
			(end -0.299974 0.150114)
			(stroke
				(width 0.1)
				(type default)
			)
			(layer "F.Fab")
		)
		(fp_line
			(start -0.299974 0.150114)
			(end -0.299974 -0.150114)
			(stroke
				(width 0.1)
				(type default)
			)
			(layer "F.Fab")
		)
		(pad "1" smd rect
			(at -0.2667 0 90)
			(size 0.3048 0.381)
			(layers "F.Cu" "F.Mask" "F.Paste")
			(net "P5E_CPU0_G3_TX_C_DP<3>")
		)
		(pad "2" smd rect
			(at 0.2667 0 90)
			(size 0.3048 0.381)
			(layers "F.Cu" "F.Mask" "F.Paste")
			(net "P5E_CPU0_G3_TX_DP<3>")
		)
	)
)
